FILE_TYPE = CONNECTIVITY;
{Allegro Design Entry HDL 17.2-2016 S081 (4005846) 1/11/2022}
"PAGE_NUMBER" = 22;
0"NC";
1"M_C_CPU0_SA_CA<6:0>";
2"M_C_CPU0_SA_CS_N<3:0>";
3"M_C_CPU0_SA_DQS_DN<9:0>";
4"M_C_CPU0_SA_DQS_DP<9:0>";
5"M_C_CPU0_SB_CA<6:0>";
6"M_C_CPU0_SB_CS_N<3:0>";
7"M_C_CPU0_SB_DQS_DN<9:0>";
8"M_C_CPU0_SB_DQS_DP<9:0>";
9"M_C_CPU0_SB_CB<7:0>";
10"M_C_CPU0_SB_DQ<31:0>";
11"M_C_CPU0_SA_CB<7:0>";
12"M_C_CPU0_SA_DQ<31:0>";
13"M_C_CPU0_CLK_DP<1:0>";
14"M_C_CPU0_CLK_DN<1:0>";
15"M_C_CPU0_CLK_DN<1>";
16"M_C_CPU0_CLK_DN<0>";
17"M_C_CPU0_CLK_DP<1>";
18"M_C_CPU0_CLK_DP<0>";
19"M_C_CPU0_SA_DQ<31>";
20"M_C_CPU0_SA_DQ<30>";
21"M_C_CPU0_SA_DQ<29>";
22"M_C_CPU0_SA_DQ<28>";
23"M_C_CPU0_SA_DQ<27>";
24"M_C_CPU0_SA_DQ<26>";
25"M_C_CPU0_SA_DQ<25>";
26"M_C_CPU0_SA_DQ<24>";
27"M_C_CPU0_SA_DQ<23>";
28"M_C_CPU0_SA_DQ<22>";
29"M_C_CPU0_SA_DQ<21>";
30"M_C_CPU0_SA_DQ<20>";
31"M_C_CPU0_SA_DQ<19>";
32"M_C_CPU0_SA_DQ<18>";
33"M_C_CPU0_SA_DQ<17>";
34"M_C_CPU0_SA_DQ<16>";
35"M_C_CPU0_SA_DQ<15>";
36"M_C_CPU0_SA_DQ<14>";
37"M_C_CPU0_SA_DQ<13>";
38"M_C_CPU0_SA_DQ<12>";
39"M_C_CPU0_SA_DQ<11>";
40"M_C_CPU0_SA_DQ<10>";
41"M_C_CPU0_SA_DQ<9>";
42"M_C_CPU0_SA_DQ<8>";
43"M_C_CPU0_SA_DQ<7>";
44"M_C_CPU0_SA_DQ<6>";
45"M_C_CPU0_SA_DQ<5>";
46"M_C_CPU0_SA_DQ<4>";
47"M_C_CPU0_SA_DQ<3>";
48"M_C_CPU0_SA_DQ<2>";
49"M_C_CPU0_SA_DQ<1>";
50"M_C_CPU0_SA_DQ<0>";
51"M_C_CPU0_SA_CB<7>";
52"M_C_CPU0_SA_CB<6>";
53"M_C_CPU0_SA_CB<5>";
54"M_C_CPU0_SA_CB<4>";
55"M_C_CPU0_SA_CB<3>";
56"M_C_CPU0_SA_CB<2>";
57"M_C_CPU0_SA_CB<1>";
58"M_C_CPU0_SA_CB<0>";
59"M_C_CPU0_SB_DQ<31>";
60"M_C_CPU0_SB_DQ<30>";
61"M_C_CPU0_SB_DQ<29>";
62"M_C_CPU0_SB_DQ<28>";
63"M_C_CPU0_SB_DQ<27>";
64"M_C_CPU0_SB_DQ<26>";
65"M_C_CPU0_SB_DQ<25>";
66"M_C_CPU0_SB_DQ<24>";
67"M_C_CPU0_SB_DQ<23>";
68"M_C_CPU0_SB_DQ<22>";
69"M_C_CPU0_SB_DQ<21>";
70"M_C_CPU0_SB_DQ<20>";
71"M_C_CPU0_SB_DQ<19>";
72"M_C_CPU0_SB_DQ<18>";
73"M_C_CPU0_SB_DQ<17>";
74"M_C_CPU0_SB_DQ<16>";
75"M_C_CPU0_SB_DQ<15>";
76"M_C_CPU0_SB_DQ<14>";
77"M_C_CPU0_SB_DQ<13>";
78"M_C_CPU0_SB_DQ<12>";
79"M_C_CPU0_SB_DQ<11>";
80"M_C_CPU0_SB_DQ<10>";
81"M_C_CPU0_SB_DQ<9>";
82"M_C_CPU0_SB_DQ<8>";
83"M_C_CPU0_SB_DQ<7>";
84"M_C_CPU0_SB_DQ<6>";
85"M_C_CPU0_SB_DQ<5>";
86"M_C_CPU0_SB_DQ<4>";
87"M_C_CPU0_SB_DQ<3>";
88"M_C_CPU0_SB_DQ<2>";
89"M_C_CPU0_SB_DQ<1>";
90"M_C_CPU0_SB_DQ<0>";
91"M_C_CPU0_SB_CB<7>";
92"M_C_CPU0_SB_CB<6>";
93"M_C_CPU0_SB_CB<5>";
94"M_C_CPU0_SB_CB<4>";
95"M_C_CPU0_SB_CB<3>";
96"M_C_CPU0_SB_CB<2>";
97"M_C_CPU0_SB_CB<1>";
98"M_C_CPU0_SB_CB<0>";
99"M_C_CPU0_SB_PAR";
100"M_C_CPU0_SB_DQS_DP<0>";
101"M_C_CPU0_SB_DQS_DP<1>";
102"M_C_CPU0_SB_DQS_DP<2>";
103"M_C_CPU0_SB_DQS_DP<3>";
104"M_C_CPU0_SB_DQS_DP<4>";
105"M_C_CPU0_SB_DQS_DP<5>";
106"M_C_CPU0_SB_DQS_DP<6>";
107"M_C_CPU0_SB_DQS_DP<7>";
108"M_C_CPU0_SB_DQS_DP<8>";
109"M_C_CPU0_SB_DQS_DP<9>";
110"M_C_CPU0_SB_DQS_DN<0>";
111"M_C_CPU0_SB_DQS_DN<1>";
112"M_C_CPU0_SB_DQS_DN<2>";
113"M_C_CPU0_SB_DQS_DN<3>";
114"M_C_CPU0_SB_DQS_DN<4>";
115"M_C_CPU0_SB_DQS_DN<5>";
116"M_C_CPU0_SB_DQS_DN<6>";
117"M_C_CPU0_SB_DQS_DN<7>";
118"M_C_CPU0_SB_DQS_DN<8>";
119"M_C_CPU0_SB_DQS_DN<9>";
120"M_C_CPU0_SB_CS_N<0>";
121"M_C_CPU0_SB_CS_N<1>";
122"M_C_CPU0_SB_CS_N<2>";
123"M_C_CPU0_SB_CS_N<3>";
124"M_C_CPU0_SB_CA<0>";
125"M_C_CPU0_SB_CA<1>";
126"M_C_CPU0_SB_CA<2>";
127"M_C_CPU0_SB_CA<3>";
128"M_C_CPU0_SB_CA<4>";
129"M_C_CPU0_SB_CA<5>";
130"M_C_CPU0_SB_CA<6>";
131"M_C_CPU0_SA_PAR";
132"M_C_CPU0_SA_DQS_DP<0>";
133"M_C_CPU0_SA_DQS_DP<1>";
134"M_C_CPU0_SA_DQS_DP<2>";
135"M_C_CPU0_SA_DQS_DP<3>";
136"M_C_CPU0_SA_DQS_DP<4>";
137"M_C_CPU0_SA_DQS_DP<5>";
138"M_C_CPU0_SA_DQS_DP<6>";
139"M_C_CPU0_SA_DQS_DP<7>";
140"M_C_CPU0_SA_DQS_DP<8>";
141"M_C_CPU0_SA_DQS_DP<9>";
142"M_C_CPU0_SA_DQS_DN<0>";
143"M_C_CPU0_SA_DQS_DN<1>";
144"M_C_CPU0_SA_DQS_DN<2>";
145"M_C_CPU0_SA_DQS_DN<3>";
146"M_C_CPU0_SA_DQS_DN<4>";
147"M_C_CPU0_SA_DQS_DN<5>";
148"M_C_CPU0_SA_DQS_DN<6>";
149"M_C_CPU0_SA_DQS_DN<7>";
150"M_C_CPU0_SA_DQS_DN<8>";
151"M_C_CPU0_SA_DQS_DN<9>";
152"M_C_CPU0_SA_CS_N<0>";
153"M_C_CPU0_SA_CS_N<1>";
154"M_C_CPU0_SA_CS_N<2>";
155"M_C_CPU0_SA_CS_N<3>";
156"M_C_CPU0_SA_CA<0>";
157"M_C_CPU0_SA_CA<1>";
158"M_C_CPU0_SA_CA<2>";
159"M_C_CPU0_SA_CA<3>";
160"M_C_CPU0_SA_CA<4>";
161"M_C_CPU0_SA_CA<5>";
162"M_C_CPU0_SA_CA<6>";
163"M_C_CPU0_SB_RSP<0>";
164"M_C_CPU0_SB_RSP<1>";
165"M_C_CPU0_SA_RSP<0>";
166"M_C_CPU0_SA_RSP<1>";
167"M_C_CPU0_ALERT_N";
%"TAP"
"1","(0,-325)","2","standard","I10";
;
CDS_LIB"standard"
BODY_TYPE"PLUMBING"
HDL_TAP"TRUE";
"B \NAC \NWC"9;
"S \NAC"
BN"0"98;
%"TAP"
"1","(3425,175)","0","standard","I100";
;
CDS_LIB"standard"
BODY_TYPE"PLUMBING"
HDL_TAP"TRUE";
"B \NAC \NWC"2;
"S \NAC"
BN"0"152;
%"TAP"
"1","(3425,275)","0","standard","I101";
;
CDS_LIB"standard"
BODY_TYPE"PLUMBING"
HDL_TAP"TRUE";
"B \NAC \NWC"2;
"S \NAC"
BN"2"154;
%"TAP"
"1","(3425,225)","0","standard","I102";
;
CDS_LIB"standard"
BODY_TYPE"PLUMBING"
HDL_TAP"TRUE";
"B \NAC \NWC"2;
"S \NAC"
BN"1"153;
%"TAP"
"1","(3425,325)","0","standard","I103";
;
CDS_LIB"standard"
BODY_TYPE"PLUMBING"
HDL_TAP"TRUE";
"B \NAC \NWC"2;
"S \NAC"
BN"3"155;
%"TAP"
"1","(3425,575)","0","standard","I104";
;
CDS_LIB"standard"
BODY_TYPE"PLUMBING"
HDL_TAP"TRUE";
"B \NAC \NWC"5;
"S \NAC"
BN"1"125;
%"TAP"
"1","(3425,525)","0","standard","I105";
;
CDS_LIB"standard"
BODY_TYPE"PLUMBING"
HDL_TAP"TRUE";
"B \NAC \NWC"5;
"S \NAC"
BN"0"124;
%"TAP"
"1","(3425,625)","0","standard","I106";
;
CDS_LIB"standard"
BODY_TYPE"PLUMBING"
HDL_TAP"TRUE";
"B \NAC \NWC"5;
"S \NAC"
BN"2"126;
%"TAP"
"1","(3425,825)","0","standard","I107";
;
CDS_LIB"standard"
BODY_TYPE"PLUMBING"
HDL_TAP"TRUE";
"B \NAC \NWC"5;
"S \NAC"
BN"6"130;
%"TAP"
"1","(3425,775)","0","standard","I108";
;
CDS_LIB"standard"
BODY_TYPE"PLUMBING"
HDL_TAP"TRUE";
"B \NAC \NWC"5;
"S \NAC"
BN"5"129;
%"TAP"
"1","(3425,725)","0","standard","I109";
;
CDS_LIB"standard"
BODY_TYPE"PLUMBING"
HDL_TAP"TRUE";
"B \NAC \NWC"5;
"S \NAC"
BN"4"128;
%"TAP"
"1","(0,-225)","2","standard","I11";
;
CDS_LIB"standard"
BODY_TYPE"PLUMBING"
HDL_TAP"TRUE";
"B \NAC \NWC"9;
"S \NAC"
BN"2"96;
%"TAP"
"1","(3425,675)","0","standard","I110";
;
CDS_LIB"standard"
BODY_TYPE"PLUMBING"
HDL_TAP"TRUE";
"B \NAC \NWC"5;
"S \NAC"
BN"3"127;
%"TAP"
"1","(3425,1075)","0","standard","I111";
;
CDS_LIB"standard"
BODY_TYPE"PLUMBING"
HDL_TAP"TRUE";
"B \NAC \NWC"1;
"S \NAC"
BN"1"157;
%"TAP"
"1","(3425,1125)","0","standard","I112";
;
CDS_LIB"standard"
BODY_TYPE"PLUMBING"
HDL_TAP"TRUE";
"B \NAC \NWC"1;
"S \NAC"
BN"2"158;
%"TAP"
"1","(3425,1175)","0","standard","I113";
;
CDS_LIB"standard"
BODY_TYPE"PLUMBING"
HDL_TAP"TRUE";
"B \NAC \NWC"1;
"S \NAC"
BN"3"159;
%"TAP"
"1","(3425,1025)","0","standard","I114";
;
CDS_LIB"standard"
BODY_TYPE"PLUMBING"
HDL_TAP"TRUE";
"B \NAC \NWC"1;
"S \NAC"
BN"0"156;
%"TAP"
"1","(3425,1225)","0","standard","I115";
;
CDS_LIB"standard"
BODY_TYPE"PLUMBING"
HDL_TAP"TRUE";
"B \NAC \NWC"1;
"S \NAC"
BN"4"160;
%"TAP"
"1","(3425,1325)","0","standard","I116";
;
CDS_LIB"standard"
BODY_TYPE"PLUMBING"
HDL_TAP"TRUE";
"B \NAC \NWC"1;
"S \NAC"
BN"6"162;
%"TAP"
"1","(3425,1275)","0","standard","I117";
;
CDS_LIB"standard"
BODY_TYPE"PLUMBING"
HDL_TAP"TRUE";
"B \NAC \NWC"1;
"S \NAC"
BN"5"161;
%"TAP"
"1","(3425,1525)","0","standard","I118";
;
CDS_LIB"standard"
BODY_TYPE"PLUMBING"
HDL_TAP"TRUE";
"B \NAC \NWC"7;
"S \NAC"
BN"1"111;
%"TAP"
"1","(3425,1675)","0","standard","I119";
;
CDS_LIB"standard"
BODY_TYPE"PLUMBING"
HDL_TAP"TRUE";
"B \NAC \NWC"7;
"S \NAC"
BN"4"114;
%"TAP"
"1","(0,-175)","2","standard","I12";
;
CDS_LIB"standard"
BODY_TYPE"PLUMBING"
HDL_TAP"TRUE";
"B \NAC \NWC"9;
"S \NAC"
BN"3"95;
%"TAP"
"1","(3425,1625)","0","standard","I120";
;
CDS_LIB"standard"
BODY_TYPE"PLUMBING"
HDL_TAP"TRUE";
"B \NAC \NWC"7;
"S \NAC"
BN"3"113;
%"TAP"
"1","(3425,1575)","0","standard","I121";
;
CDS_LIB"standard"
BODY_TYPE"PLUMBING"
HDL_TAP"TRUE";
"B \NAC \NWC"7;
"S \NAC"
BN"2"112;
%"TAP"
"1","(3425,1475)","0","standard","I122";
;
CDS_LIB"standard"
BODY_TYPE"PLUMBING"
HDL_TAP"TRUE";
"B \NAC \NWC"7;
"S \NAC"
BN"0"110;
%"TAP"
"1","(3425,1925)","0","standard","I123";
;
CDS_LIB"standard"
BODY_TYPE"PLUMBING"
HDL_TAP"TRUE";
"B \NAC \NWC"7;
"S \NAC"
BN"9"119;
%"TAP"
"1","(3425,1875)","0","standard","I124";
;
CDS_LIB"standard"
BODY_TYPE"PLUMBING"
HDL_TAP"TRUE";
"B \NAC \NWC"7;
"S \NAC"
BN"8"118;
%"TAP"
"1","(3425,1825)","0","standard","I125";
;
CDS_LIB"standard"
BODY_TYPE"PLUMBING"
HDL_TAP"TRUE";
"B \NAC \NWC"7;
"S \NAC"
BN"7"117;
%"TAP"
"1","(3425,1775)","0","standard","I126";
;
CDS_LIB"standard"
BODY_TYPE"PLUMBING"
HDL_TAP"TRUE";
"B \NAC \NWC"7;
"S \NAC"
BN"6"116;
%"TAP"
"1","(3425,1725)","0","standard","I127";
;
CDS_LIB"standard"
BODY_TYPE"PLUMBING"
HDL_TAP"TRUE";
"B \NAC \NWC"7;
"S \NAC"
BN"5"115;
%"TAP"
"1","(3425,2075)","0","standard","I128";
;
CDS_LIB"standard"
BODY_TYPE"PLUMBING"
HDL_TAP"TRUE";
"B \NAC \NWC"8;
"S \NAC"
BN"1"101;
%"TAP"
"1","(3425,2125)","0","standard","I129";
;
CDS_LIB"standard"
BODY_TYPE"PLUMBING"
HDL_TAP"TRUE";
"B \NAC \NWC"8;
"S \NAC"
BN"2"102;
%"TAP"
"1","(0,-125)","2","standard","I13";
;
CDS_LIB"standard"
BODY_TYPE"PLUMBING"
HDL_TAP"TRUE";
"B \NAC \NWC"9;
"S \NAC"
BN"4"94;
%"TAP"
"1","(3425,2175)","0","standard","I130";
;
CDS_LIB"standard"
BODY_TYPE"PLUMBING"
HDL_TAP"TRUE";
"B \NAC \NWC"8;
"S \NAC"
BN"3"103;
%"TAP"
"1","(3425,2025)","0","standard","I131";
;
CDS_LIB"standard"
BODY_TYPE"PLUMBING"
HDL_TAP"TRUE";
"B \NAC \NWC"8;
"S \NAC"
BN"0"100;
%"TAP"
"1","(3425,2275)","0","standard","I132";
;
CDS_LIB"standard"
BODY_TYPE"PLUMBING"
HDL_TAP"TRUE";
"B \NAC \NWC"8;
"S \NAC"
BN"5"105;
%"TAP"
"1","(3425,2425)","0","standard","I133";
;
CDS_LIB"standard"
BODY_TYPE"PLUMBING"
HDL_TAP"TRUE";
"B \NAC \NWC"8;
"S \NAC"
BN"8"108;
%"TAP"
"1","(3425,2375)","0","standard","I134";
;
CDS_LIB"standard"
BODY_TYPE"PLUMBING"
HDL_TAP"TRUE";
"B \NAC \NWC"8;
"S \NAC"
BN"7"107;
%"TAP"
"1","(3425,2325)","0","standard","I135";
;
CDS_LIB"standard"
BODY_TYPE"PLUMBING"
HDL_TAP"TRUE";
"B \NAC \NWC"8;
"S \NAC"
BN"6"106;
%"TAP"
"1","(3425,2225)","0","standard","I136";
;
CDS_LIB"standard"
BODY_TYPE"PLUMBING"
HDL_TAP"TRUE";
"B \NAC \NWC"8;
"S \NAC"
BN"4"104;
%"TAP"
"1","(3425,2475)","0","standard","I137";
;
CDS_LIB"standard"
BODY_TYPE"PLUMBING"
HDL_TAP"TRUE";
"B \NAC \NWC"8;
"S \NAC"
BN"9"109;
%"TAP"
"1","(3425,2625)","0","standard","I138";
;
CDS_LIB"standard"
BODY_TYPE"PLUMBING"
HDL_TAP"TRUE";
"B \NAC \NWC"3;
"S \NAC"
BN"0"142;
%"TAP"
"1","(3425,2675)","0","standard","I139";
;
CDS_LIB"standard"
BODY_TYPE"PLUMBING"
HDL_TAP"TRUE";
"B \NAC \NWC"3;
"S \NAC"
BN"1"143;
%"TAP"
"1","(0,-75)","2","standard","I14";
;
CDS_LIB"standard"
BODY_TYPE"PLUMBING"
HDL_TAP"TRUE";
"B \NAC \NWC"9;
"S \NAC"
BN"5"93;
%"TAP"
"1","(3425,2775)","0","standard","I140";
;
CDS_LIB"standard"
BODY_TYPE"PLUMBING"
HDL_TAP"TRUE";
"B \NAC \NWC"3;
"S \NAC"
BN"3"145;
%"TAP"
"1","(3425,2925)","0","standard","I141";
;
CDS_LIB"standard"
BODY_TYPE"PLUMBING"
HDL_TAP"TRUE";
"B \NAC \NWC"3;
"S \NAC"
BN"6"148;
%"TAP"
"1","(3425,2975)","0","standard","I142";
;
CDS_LIB"standard"
BODY_TYPE"PLUMBING"
HDL_TAP"TRUE";
"B \NAC \NWC"3;
"S \NAC"
BN"7"149;
%"TAP"
"1","(3425,2875)","0","standard","I143";
;
CDS_LIB"standard"
BODY_TYPE"PLUMBING"
HDL_TAP"TRUE";
"B \NAC \NWC"3;
"S \NAC"
BN"5"147;
%"TAP"
"1","(3425,2825)","0","standard","I144";
;
CDS_LIB"standard"
BODY_TYPE"PLUMBING"
HDL_TAP"TRUE";
"B \NAC \NWC"3;
"S \NAC"
BN"4"146;
%"TAP"
"1","(3425,2725)","0","standard","I145";
;
CDS_LIB"standard"
BODY_TYPE"PLUMBING"
HDL_TAP"TRUE";
"B \NAC \NWC"3;
"S \NAC"
BN"2"144;
%"TAP"
"1","(3425,3025)","0","standard","I146";
;
CDS_LIB"standard"
BODY_TYPE"PLUMBING"
HDL_TAP"TRUE";
"B \NAC \NWC"3;
"S \NAC"
BN"8"150;
%"TAP"
"1","(3425,3225)","0","standard","I147";
;
CDS_LIB"standard"
BODY_TYPE"PLUMBING"
HDL_TAP"TRUE";
"B \NAC \NWC"4;
"S \NAC"
BN"1"133;
%"TAP"
"1","(3425,3175)","0","standard","I148";
;
CDS_LIB"standard"
BODY_TYPE"PLUMBING"
HDL_TAP"TRUE";
"B \NAC \NWC"4;
"S \NAC"
BN"0"132;
%"TAP"
"1","(3425,3075)","0","standard","I149";
;
CDS_LIB"standard"
BODY_TYPE"PLUMBING"
HDL_TAP"TRUE";
"B \NAC \NWC"3;
"S \NAC"
BN"9"151;
%"TAP"
"1","(0,-25)","2","standard","I15";
;
CDS_LIB"standard"
BODY_TYPE"PLUMBING"
HDL_TAP"TRUE";
"B \NAC \NWC"9;
"S \NAC"
BN"6"92;
%"TAP"
"1","(3425,3325)","0","standard","I150";
;
CDS_LIB"standard"
BODY_TYPE"PLUMBING"
HDL_TAP"TRUE";
"B \NAC \NWC"4;
"S \NAC"
BN"3"135;
%"TAP"
"1","(3425,3475)","0","standard","I151";
;
CDS_LIB"standard"
BODY_TYPE"PLUMBING"
HDL_TAP"TRUE";
"B \NAC \NWC"4;
"S \NAC"
BN"6"138;
%"TAP"
"1","(3425,3425)","0","standard","I152";
;
CDS_LIB"standard"
BODY_TYPE"PLUMBING"
HDL_TAP"TRUE";
"B \NAC \NWC"4;
"S \NAC"
BN"5"137;
%"TAP"
"1","(3425,3275)","0","standard","I153";
;
CDS_LIB"standard"
BODY_TYPE"PLUMBING"
HDL_TAP"TRUE";
"B \NAC \NWC"4;
"S \NAC"
BN"2"134;
%"TAP"
"1","(3425,3375)","0","standard","I154";
;
CDS_LIB"standard"
BODY_TYPE"PLUMBING"
HDL_TAP"TRUE";
"B \NAC \NWC"4;
"S \NAC"
BN"4"136;
%"TAP"
"1","(3425,3525)","0","standard","I155";
;
CDS_LIB"standard"
BODY_TYPE"PLUMBING"
HDL_TAP"TRUE";
"B \NAC \NWC"4;
"S \NAC"
BN"7"139;
%"TAP"
"1","(3425,3575)","0","standard","I156";
;
CDS_LIB"standard"
BODY_TYPE"PLUMBING"
HDL_TAP"TRUE";
"B \NAC \NWC"4;
"S \NAC"
BN"8"140;
%"TAP"
"1","(3425,3625)","0","standard","I157";
;
CDS_LIB"standard"
BODY_TYPE"PLUMBING"
HDL_TAP"TRUE";
"B \NAC \NWC"4;
"S \NAC"
BN"9"141;
%"TAP"
"1","(0,25)","2","standard","I16";
;
CDS_LIB"standard"
BODY_TYPE"PLUMBING"
HDL_TAP"TRUE";
"B \NAC \NWC"9;
"S \NAC"
BN"7"91;
%"SOCKET4677_AZIF0045P001C01CS"
"10","(1725,1525)","0","pure_quanta","I169";
;
PART_NUMBER"DGA^7000023"
PART_TYPE"SMLF"
MATERIAL"IO"
VALUE"SOCKET4677_AZIF0045-P001C01CS"
$LOCATION"U2"
CDS_LIB"pure_quanta"
NEEDS_NO_SIZE"TRUE"
CDS_LMAN_SYM_OUTLINE"-1100,2250,1050,-2250"
CDS_LOCATION"U2"
$SEC"10"
CDS_SEC"10";
"DDR2_SB_PAR"
$PN"AA39"99;
"DDR2_SB_ECC0"
$PN"T32"98;
"DDR2_SB_ECC1"
$PN"U31"97;
"DDR2_SB_ECC2"
$PN"Y32"96;
"DDR2_SB_ECC3"
$PN"W31"95;
"DDR2_SB_ECC4"
$PN"U35"94;
"DDR2_SB_ECC5"
$PN"T34"93;
"DDR2_SB_ECC6"
$PN"W35"92;
"DDR2_SB_ECC7"
$PN"Y34"91;
"DDR2_SB_DQS_DP0"
$PN"AD36"100;
"DDR2_SB_DQS_DP1"
$PN"AD30"101;
"DDR2_SB_DQS_DP2"
$PN"U21"102;
"DDR2_SB_DQS_DP3"
$PN"AD18"103;
"DDR2_SB_DQS_DP4"
$PN"AA33"104;
"DDR2_SB_DQS_DP5"
$PN"AH36"105;
"DDR2_SB_DQS_DP6"
$PN"AH30"106;
"DDR2_SB_DQS_DP7"
$PN"AA21"107;
"DDR2_SB_DQS_DP8"
$PN"AH18"108;
"DDR2_SB_DQS_DP9"
$PN"U33"109;
"DDR2_SB_DQS_DN0 \B"
$PN"AB36"110;
"DDR2_SB_DQS_DN1 \B"
$PN"AB30"111;
"DDR2_SB_DQS_DN2 \B"
$PN"R21"112;
"DDR2_SB_DQS_DN3 \B"
$PN"AB18"113;
"DDR2_SB_DQS_DN4 \B"
$PN"W33"114;
"DDR2_SB_DQS_DN5 \B"
$PN"AF36"115;
"DDR2_SB_DQS_DN6 \B"
$PN"AF30"116;
"DDR2_SB_DQS_DN7 \B"
$PN"W21"117;
"DDR2_SB_DQS_DN8 \B"
$PN"AF18"118;
"DDR2_SB_DQS_DN9 \B"
$PN"R33"119;
"DDR2_SB_DQ0"
$PN"AD38"90;
"DDR2_SB_DQ1"
$PN"AC37"89;
"DDR2_SB_DQ2"
$PN"AF38"88;
"DDR2_SB_DQ3"
$PN"AG37"87;
"DDR2_SB_DQ4"
$PN"AC35"86;
"DDR2_SB_DQ5"
$PN"AD34"85;
"DDR2_SB_DQ6"
$PN"AG35"84;
"DDR2_SB_DQ7"
$PN"AF34"83;
"DDR2_SB_DQ8"
$PN"AD32"82;
"DDR2_SB_DQ9"
$PN"AC31"81;
"DDR2_SB_DQ10"
$PN"AF32"80;
"DDR2_SB_DQ11"
$PN"AG31"79;
"DDR2_SB_DQ12"
$PN"AC29"78;
"DDR2_SB_DQ13"
$PN"AD28"77;
"DDR2_SB_DQ14"
$PN"AG29"76;
"DDR2_SB_DQ15"
$PN"AF28"75;
"DDR2_SB_DQ16"
$PN"U23"74;
"DDR2_SB_DQ17"
$PN"T22"73;
"DDR2_SB_DQ18"
$PN"W23"72;
"DDR2_SB_DQ19"
$PN"Y22"71;
"DDR2_SB_DQ20"
$PN"T20"70;
"DDR2_SB_DQ21"
$PN"U19"69;
"DDR2_SB_DQ22"
$PN"Y20"68;
"DDR2_SB_DQ23"
$PN"W19"67;
"DDR2_SB_DQ24"
$PN"AD20"66;
"DDR2_SB_DQ25"
$PN"AC19"65;
"DDR2_SB_DQ26"
$PN"AF20"64;
"DDR2_SB_DQ27"
$PN"AG19"63;
"DDR2_SB_DQ28"
$PN"AA17"62;
"DDR2_SB_DQ29"
$PN"AG17"61;
"DDR2_SB_DQ30"
$PN"AC17"60;
"DDR2_SB_DQ31"
$PN"AJ17"59;
"DDR2_SB_CS_N0 \B"
$PN"T38"120;
"DDR2_SB_CS_N1 \B"
$PN"U37"121;
"DDR2_SB_CS_N2 \B"
$PN"Y38"122;
"DDR2_SB_CS_N3 \B"
$PN"W37"123;
"DDR2_SB_CA0"
$PN"W48"124;
"DDR2_SB_CA1"
$PN"Y47"125;
"DDR2_SB_CA2"
$PN"U41"126;
"DDR2_SB_CA3"
$PN"W41"127;
"DDR2_SB_CA4"
$PN"T40"128;
"DDR2_SB_CA5"
$PN"Y40"129;
"DDR2_SB_CA6"
$PN"R39"130;
"DDR2_SA_PAR"
$PN"T47"131;
"DDR2_SA_ECC0"
$PN"AD57"58;
"DDR2_SA_ECC1"
$PN"AC56"57;
"DDR2_SA_ECC2"
$PN"AF57"56;
"DDR2_SA_ECC3"
$PN"AG56"55;
"DDR2_SA_ECC4"
$PN"AC54"54;
"DDR2_SA_ECC5"
$PN"AD53"53;
"DDR2_SA_ECC6"
$PN"AG54"52;
"DDR2_SA_ECC7"
$PN"AF53"51;
"DDR2_SA_DQS_DP0"
$PN"U76"132;
"DDR2_SA_DQS_DP1"
$PN"AD67"133;
"DDR2_SA_DQS_DP2"
$PN"U64"134;
"DDR2_SA_DQS_DP3"
$PN"AD61"135;
"DDR2_SA_DQS_DP4"
$PN"AB55"136;
"DDR2_SA_DQS_DP5"
$PN"AA76"137;
"DDR2_SA_DQS_DP6"
$PN"AF67"138;
"DDR2_SA_DQS_DP7"
$PN"W64"139;
"DDR2_SA_DQS_DP8"
$PN"AH61"140;
"DDR2_SA_DQS_DP9"
$PN"AF55"141;
"DDR2_SA_DQS_DN0 \B"
$PN"R76"142;
"DDR2_SA_DQS_DN1 \B"
$PN"AB67"143;
"DDR2_SA_DQS_DN2 \B"
$PN"R64"144;
"DDR2_SA_DQS_DN3 \B"
$PN"AB61"145;
"DDR2_SA_DQS_DN4 \B"
$PN"AD55"146;
"DDR2_SA_DQS_DN5 \B"
$PN"W76"147;
"DDR2_SA_DQS_DN6 \B"
$PN"AH67"148;
"DDR2_SA_DQS_DN7 \B"
$PN"AA64"149;
"DDR2_SA_DQS_DN8 \B"
$PN"AF61"150;
"DDR2_SA_DQS_DN9 \B"
$PN"AH55"151;
"DDR2_SA_DQ0"
$PN"U78"50;
"DDR2_SA_DQ1"
$PN"T77"49;
"DDR2_SA_DQ2"
$PN"W78"48;
"DDR2_SA_DQ3"
$PN"Y77"47;
"DDR2_SA_DQ4"
$PN"T75"46;
"DDR2_SA_DQ5"
$PN"U74"45;
"DDR2_SA_DQ6"
$PN"Y75"44;
"DDR2_SA_DQ7"
$PN"W74"43;
"DDR2_SA_DQ8"
$PN"AD69"42;
"DDR2_SA_DQ9"
$PN"AC68"41;
"DDR2_SA_DQ10"
$PN"AF69"40;
"DDR2_SA_DQ11"
$PN"AG68"39;
"DDR2_SA_DQ12"
$PN"AC66"38;
"DDR2_SA_DQ13"
$PN"AD65"37;
"DDR2_SA_DQ14"
$PN"AG66"36;
"DDR2_SA_DQ15"
$PN"AF65"35;
"DDR2_SA_DQ16"
$PN"U66"34;
"DDR2_SA_DQ17"
$PN"T65"33;
"DDR2_SA_DQ18"
$PN"W66"32;
"DDR2_SA_DQ19"
$PN"Y65"31;
"DDR2_SA_DQ20"
$PN"T63"30;
"DDR2_SA_DQ21"
$PN"U62"29;
"DDR2_SA_DQ22"
$PN"Y63"28;
"DDR2_SA_DQ23"
$PN"W62"27;
"DDR2_SA_DQ24"
$PN"AD63"26;
"DDR2_SA_DQ25"
$PN"AC62"25;
"DDR2_SA_DQ26"
$PN"AF63"24;
"DDR2_SA_DQ27"
$PN"AG62"23;
"DDR2_SA_DQ28"
$PN"AC60"22;
"DDR2_SA_DQ29"
$PN"AD59"21;
"DDR2_SA_DQ30"
$PN"AG60"20;
"DDR2_SA_DQ31"
$PN"AF59"19;
"DDR2_SA_CS_N0 \B"
$PN"U54"152;
"DDR2_SA_CS_N1 \B"
$PN"T53"153;
"DDR2_SA_CS_N2 \B"
$PN"W54"154;
"DDR2_SA_CS_N3 \B"
$PN"Y53"155;
"DDR2_SA_CA0"
$PN"R52"156;
"DDR2_SA_CA1"
$PN"AA52"157;
"DDR2_SA_CA2"
$PN"T51"158;
"DDR2_SA_CA3"
$PN"Y51"159;
"DDR2_SA_CA4"
$PN"U50"160;
"DDR2_SA_CA5"
$PN"W50"161;
"DDR2_SA_CA6"
$PN"U48"162;
"DDR2_CLK_DP0"
$PN"AD49"18;
"DDR2_CLK_DP1"
$PN"AH49"17;
"DDR2_CLK_DN0 \B"
$PN"AB49"16;
"DDR2_CLK_DN1 \B"
$PN"AF49"15;
"DDR2_B_RSP0"
$PN"AG48"163;
"DDR2_B_RSP1"
$PN"AF47"164;
"DDR2_A_RSP0"
$PN"AC48"165;
"DDR2_A_RSP1"
$PN"AD47"166;
"DDR2_ALERT_N \B"
$PN"AT47"167;
%"TAP"
"1","(0,75)","2","standard","I17";
;
CDS_LIB"standard"
BODY_TYPE"PLUMBING"
HDL_TAP"TRUE";
"B \NAC \NWC"10;
"S \NAC"
BN"0"90;
%"TAP"
"1","(0,125)","2","standard","I18";
;
CDS_LIB"standard"
BODY_TYPE"PLUMBING"
HDL_TAP"TRUE";
"B \NAC \NWC"10;
"S \NAC"
BN"1"89;
%"TAP"
"1","(0,175)","2","standard","I19";
;
CDS_LIB"standard"
BODY_TYPE"PLUMBING"
HDL_TAP"TRUE";
"B \NAC \NWC"10;
"S \NAC"
BN"2"88;
%"TAP"
"1","(0,225)","2","standard","I20";
;
CDS_LIB"standard"
BODY_TYPE"PLUMBING"
HDL_TAP"TRUE";
"B \NAC \NWC"10;
"S \NAC"
BN"3"87;
%"TAP"
"1","(0,275)","2","standard","I21";
;
CDS_LIB"standard"
BODY_TYPE"PLUMBING"
HDL_TAP"TRUE";
"B \NAC \NWC"10;
"S \NAC"
BN"4"86;
%"TAP"
"1","(0,375)","2","standard","I22";
;
CDS_LIB"standard"
BODY_TYPE"PLUMBING"
HDL_TAP"TRUE";
"B \NAC \NWC"10;
"S \NAC"
BN"6"84;
%"TAP"
"1","(0,325)","2","standard","I23";
;
CDS_LIB"standard"
BODY_TYPE"PLUMBING"
HDL_TAP"TRUE";
"B \NAC \NWC"10;
"S \NAC"
BN"5"85;
%"TAP"
"1","(0,425)","2","standard","I24";
;
CDS_LIB"standard"
BODY_TYPE"PLUMBING"
HDL_TAP"TRUE";
"B \NAC \NWC"10;
"S \NAC"
BN"7"83;
%"TAP"
"1","(0,475)","2","standard","I25";
;
CDS_LIB"standard"
BODY_TYPE"PLUMBING"
HDL_TAP"TRUE";
"B \NAC \NWC"10;
"S \NAC"
BN"8"82;
%"TAP"
"1","(0,525)","2","standard","I26";
;
CDS_LIB"standard"
BODY_TYPE"PLUMBING"
HDL_TAP"TRUE";
"B \NAC \NWC"10;
"S \NAC"
BN"9"81;
%"TAP"
"1","(0,575)","2","standard","I27";
;
CDS_LIB"standard"
BODY_TYPE"PLUMBING"
HDL_TAP"TRUE";
"B \NAC \NWC"10;
"S \NAC"
BN"10"80;
%"TAP"
"1","(0,625)","2","standard","I28";
;
CDS_LIB"standard"
BODY_TYPE"PLUMBING"
HDL_TAP"TRUE";
"B \NAC \NWC"10;
"S \NAC"
BN"11"79;
%"TAP"
"1","(0,675)","2","standard","I29";
;
CDS_LIB"standard"
BODY_TYPE"PLUMBING"
HDL_TAP"TRUE";
"B \NAC \NWC"10;
"S \NAC"
BN"12"78;
%"TAP"
"1","(0,-575)","2","standard","I3";
;
CDS_LIB"standard"
BODY_TYPE"PLUMBING"
HDL_TAP"TRUE";
"B \NAC \NWC"14;
"S \NAC"
BN"0"16;
%"TAP"
"1","(0,775)","2","standard","I30";
;
CDS_LIB"standard"
BODY_TYPE"PLUMBING"
HDL_TAP"TRUE";
"B \NAC \NWC"10;
"S \NAC"
BN"14"76;
%"TAP"
"1","(0,725)","2","standard","I31";
;
CDS_LIB"standard"
BODY_TYPE"PLUMBING"
HDL_TAP"TRUE";
"B \NAC \NWC"10;
"S \NAC"
BN"13"77;
%"TAP"
"1","(0,825)","2","standard","I32";
;
CDS_LIB"standard"
BODY_TYPE"PLUMBING"
HDL_TAP"TRUE";
"B \NAC \NWC"10;
"S \NAC"
BN"15"75;
%"TAP"
"1","(0,875)","2","standard","I33";
;
CDS_LIB"standard"
BODY_TYPE"PLUMBING"
HDL_TAP"TRUE";
"B \NAC \NWC"10;
"S \NAC"
BN"16"74;
%"TAP"
"1","(0,925)","2","standard","I34";
;
CDS_LIB"standard"
BODY_TYPE"PLUMBING"
HDL_TAP"TRUE";
"B \NAC \NWC"10;
"S \NAC"
BN"17"73;
%"TAP"
"1","(0,1025)","2","standard","I35";
;
CDS_LIB"standard"
BODY_TYPE"PLUMBING"
HDL_TAP"TRUE";
"B \NAC \NWC"10;
"S \NAC"
BN"19"71;
%"TAP"
"1","(0,975)","2","standard","I36";
;
CDS_LIB"standard"
BODY_TYPE"PLUMBING"
HDL_TAP"TRUE";
"B \NAC \NWC"10;
"S \NAC"
BN"18"72;
%"TAP"
"1","(0,1075)","2","standard","I37";
;
CDS_LIB"standard"
BODY_TYPE"PLUMBING"
HDL_TAP"TRUE";
"B \NAC \NWC"10;
"S \NAC"
BN"20"70;
%"TAP"
"1","(0,1125)","2","standard","I38";
;
CDS_LIB"standard"
BODY_TYPE"PLUMBING"
HDL_TAP"TRUE";
"B \NAC \NWC"10;
"S \NAC"
BN"21"69;
%"TAP"
"1","(0,1175)","2","standard","I39";
;
CDS_LIB"standard"
BODY_TYPE"PLUMBING"
HDL_TAP"TRUE";
"B \NAC \NWC"10;
"S \NAC"
BN"22"68;
%"TAP"
"1","(0,-525)","2","standard","I4";
;
CDS_LIB"standard"
BODY_TYPE"PLUMBING"
HDL_TAP"TRUE";
"B \NAC \NWC"14;
"S \NAC"
BN"1"15;
%"TAP"
"1","(0,1275)","2","standard","I40";
;
CDS_LIB"standard"
BODY_TYPE"PLUMBING"
HDL_TAP"TRUE";
"B \NAC \NWC"10;
"S \NAC"
BN"24"66;
%"TAP"
"1","(0,1225)","2","standard","I41";
;
CDS_LIB"standard"
BODY_TYPE"PLUMBING"
HDL_TAP"TRUE";
"B \NAC \NWC"10;
"S \NAC"
BN"23"67;
%"TAP"
"1","(0,1325)","2","standard","I42";
;
CDS_LIB"standard"
BODY_TYPE"PLUMBING"
HDL_TAP"TRUE";
"B \NAC \NWC"10;
"S \NAC"
BN"25"65;
%"TAP"
"1","(0,1375)","2","standard","I43";
;
CDS_LIB"standard"
BODY_TYPE"PLUMBING"
HDL_TAP"TRUE";
"B \NAC \NWC"10;
"S \NAC"
BN"26"64;
%"TAP"
"1","(0,1425)","2","standard","I44";
;
CDS_LIB"standard"
BODY_TYPE"PLUMBING"
HDL_TAP"TRUE";
"B \NAC \NWC"10;
"S \NAC"
BN"27"63;
%"TAP"
"1","(0,1475)","2","standard","I45";
;
CDS_LIB"standard"
BODY_TYPE"PLUMBING"
HDL_TAP"TRUE";
"B \NAC \NWC"10;
"S \NAC"
BN"28"62;
%"TAP"
"1","(0,1525)","2","standard","I46";
;
CDS_LIB"standard"
BODY_TYPE"PLUMBING"
HDL_TAP"TRUE";
"B \NAC \NWC"10;
"S \NAC"
BN"29"61;
%"TAP"
"1","(0,1625)","2","standard","I47";
;
CDS_LIB"standard"
BODY_TYPE"PLUMBING"
HDL_TAP"TRUE";
"B \NAC \NWC"10;
"S \NAC"
BN"31"59;
%"TAP"
"1","(0,1575)","2","standard","I48";
;
CDS_LIB"standard"
BODY_TYPE"PLUMBING"
HDL_TAP"TRUE";
"B \NAC \NWC"10;
"S \NAC"
BN"30"60;
%"TAP"
"1","(0,1675)","2","standard","I49";
;
CDS_LIB"standard"
BODY_TYPE"PLUMBING"
HDL_TAP"TRUE";
"B \NAC \NWC"11;
"S \NAC"
BN"0"58;
%"TAP"
"1","(0,-425)","2","standard","I5";
;
CDS_LIB"standard"
BODY_TYPE"PLUMBING"
HDL_TAP"TRUE";
"B \NAC \NWC"13;
"S \NAC"
BN"1"17;
%"TAP"
"1","(0,1725)","2","standard","I52";
;
CDS_LIB"standard"
BODY_TYPE"PLUMBING"
HDL_TAP"TRUE";
"B \NAC \NWC"11;
"S \NAC"
BN"1"57;
%"TAP"
"1","(0,1775)","2","standard","I53";
;
CDS_LIB"standard"
BODY_TYPE"PLUMBING"
HDL_TAP"TRUE";
"B \NAC \NWC"11;
"S \NAC"
BN"2"56;
%"TAP"
"1","(0,1825)","2","standard","I54";
;
CDS_LIB"standard"
BODY_TYPE"PLUMBING"
HDL_TAP"TRUE";
"B \NAC \NWC"11;
"S \NAC"
BN"3"55;
%"TAP"
"1","(0,1925)","2","standard","I55";
;
CDS_LIB"standard"
BODY_TYPE"PLUMBING"
HDL_TAP"TRUE";
"B \NAC \NWC"11;
"S \NAC"
BN"5"53;
%"TAP"
"1","(0,1875)","2","standard","I56";
;
CDS_LIB"standard"
BODY_TYPE"PLUMBING"
HDL_TAP"TRUE";
"B \NAC \NWC"11;
"S \NAC"
BN"4"54;
%"TAP"
"1","(0,1975)","2","standard","I57";
;
CDS_LIB"standard"
BODY_TYPE"PLUMBING"
HDL_TAP"TRUE";
"B \NAC \NWC"11;
"S \NAC"
BN"6"52;
%"TAP"
"1","(0,2025)","2","standard","I58";
;
CDS_LIB"standard"
BODY_TYPE"PLUMBING"
HDL_TAP"TRUE";
"B \NAC \NWC"11;
"S \NAC"
BN"7"51;
%"TAP"
"1","(0,2075)","2","standard","I59";
;
CDS_LIB"standard"
BODY_TYPE"PLUMBING"
HDL_TAP"TRUE";
"B \NAC \NWC"12;
"S \NAC"
BN"0"50;
%"TAP"
"1","(0,-475)","2","standard","I6";
;
CDS_LIB"standard"
BODY_TYPE"PLUMBING"
HDL_TAP"TRUE";
"B \NAC \NWC"13;
"S \NAC"
BN"0"18;
%"TAP"
"1","(0,2125)","2","standard","I60";
;
CDS_LIB"standard"
BODY_TYPE"PLUMBING"
HDL_TAP"TRUE";
"B \NAC \NWC"12;
"S \NAC"
BN"1"49;
%"TAP"
"1","(0,2175)","2","standard","I61";
;
CDS_LIB"standard"
BODY_TYPE"PLUMBING"
HDL_TAP"TRUE";
"B \NAC \NWC"12;
"S \NAC"
BN"2"48;
%"TAP"
"1","(0,2225)","2","standard","I62";
;
CDS_LIB"standard"
BODY_TYPE"PLUMBING"
HDL_TAP"TRUE";
"B \NAC \NWC"12;
"S \NAC"
BN"3"47;
%"TAP"
"1","(0,2275)","2","standard","I63";
;
CDS_LIB"standard"
BODY_TYPE"PLUMBING"
HDL_TAP"TRUE";
"B \NAC \NWC"12;
"S \NAC"
BN"4"46;
%"TAP"
"1","(0,2325)","2","standard","I64";
;
CDS_LIB"standard"
BODY_TYPE"PLUMBING"
HDL_TAP"TRUE";
"B \NAC \NWC"12;
"S \NAC"
BN"5"45;
%"TAP"
"1","(0,2425)","2","standard","I65";
;
CDS_LIB"standard"
BODY_TYPE"PLUMBING"
HDL_TAP"TRUE";
"B \NAC \NWC"12;
"S \NAC"
BN"7"43;
%"TAP"
"1","(0,2375)","2","standard","I66";
;
CDS_LIB"standard"
BODY_TYPE"PLUMBING"
HDL_TAP"TRUE";
"B \NAC \NWC"12;
"S \NAC"
BN"6"44;
%"TAP"
"1","(0,2475)","2","standard","I67";
;
CDS_LIB"standard"
BODY_TYPE"PLUMBING"
HDL_TAP"TRUE";
"B \NAC \NWC"12;
"S \NAC"
BN"8"42;
%"TAP"
"1","(0,2525)","2","standard","I68";
;
CDS_LIB"standard"
BODY_TYPE"PLUMBING"
HDL_TAP"TRUE";
"B \NAC \NWC"12;
"S \NAC"
BN"9"41;
%"TAP"
"1","(0,2575)","2","standard","I69";
;
CDS_LIB"standard"
BODY_TYPE"PLUMBING"
HDL_TAP"TRUE";
"B \NAC \NWC"12;
"S \NAC"
BN"10"40;
%"TAP"
"1","(0,2625)","2","standard","I70";
;
CDS_LIB"standard"
BODY_TYPE"PLUMBING"
HDL_TAP"TRUE";
"B \NAC \NWC"12;
"S \NAC"
BN"11"39;
%"TAP"
"1","(0,2675)","2","standard","I71";
;
CDS_LIB"standard"
BODY_TYPE"PLUMBING"
HDL_TAP"TRUE";
"B \NAC \NWC"12;
"S \NAC"
BN"12"38;
%"TAP"
"1","(0,2725)","2","standard","I72";
;
CDS_LIB"standard"
BODY_TYPE"PLUMBING"
HDL_TAP"TRUE";
"B \NAC \NWC"12;
"S \NAC"
BN"13"37;
%"TAP"
"1","(0,2775)","2","standard","I73";
;
CDS_LIB"standard"
BODY_TYPE"PLUMBING"
HDL_TAP"TRUE";
"B \NAC \NWC"12;
"S \NAC"
BN"14"36;
%"TAP"
"1","(0,2825)","2","standard","I74";
;
CDS_LIB"standard"
BODY_TYPE"PLUMBING"
HDL_TAP"TRUE";
"B \NAC \NWC"12;
"S \NAC"
BN"15"35;
%"TAP"
"1","(0,2925)","2","standard","I75";
;
CDS_LIB"standard"
BODY_TYPE"PLUMBING"
HDL_TAP"TRUE";
"B \NAC \NWC"12;
"S \NAC"
BN"17"33;
%"TAP"
"1","(0,2875)","2","standard","I76";
;
CDS_LIB"standard"
BODY_TYPE"PLUMBING"
HDL_TAP"TRUE";
"B \NAC \NWC"12;
"S \NAC"
BN"16"34;
%"TAP"
"1","(0,2975)","2","standard","I77";
;
CDS_LIB"standard"
BODY_TYPE"PLUMBING"
HDL_TAP"TRUE";
"B \NAC \NWC"12;
"S \NAC"
BN"18"32;
%"TAP"
"1","(0,3075)","2","standard","I78";
;
CDS_LIB"standard"
BODY_TYPE"PLUMBING"
HDL_TAP"TRUE";
"B \NAC \NWC"12;
"S \NAC"
BN"20"30;
%"TAP"
"1","(0,3025)","2","standard","I79";
;
CDS_LIB"standard"
BODY_TYPE"PLUMBING"
HDL_TAP"TRUE";
"B \NAC \NWC"12;
"S \NAC"
BN"19"31;
%"TAP"
"1","(0,3175)","2","standard","I80";
;
CDS_LIB"standard"
BODY_TYPE"PLUMBING"
HDL_TAP"TRUE";
"B \NAC \NWC"12;
"S \NAC"
BN"22"28;
%"TAP"
"1","(0,3125)","2","standard","I81";
;
CDS_LIB"standard"
BODY_TYPE"PLUMBING"
HDL_TAP"TRUE";
"B \NAC \NWC"12;
"S \NAC"
BN"21"29;
%"TAP"
"1","(0,3225)","2","standard","I82";
;
CDS_LIB"standard"
BODY_TYPE"PLUMBING"
HDL_TAP"TRUE";
"B \NAC \NWC"12;
"S \NAC"
BN"23"27;
%"TAP"
"1","(0,3325)","2","standard","I83";
;
CDS_LIB"standard"
BODY_TYPE"PLUMBING"
HDL_TAP"TRUE";
"B \NAC \NWC"12;
"S \NAC"
BN"25"25;
%"TAP"
"1","(0,3275)","2","standard","I84";
;
CDS_LIB"standard"
BODY_TYPE"PLUMBING"
HDL_TAP"TRUE";
"B \NAC \NWC"12;
"S \NAC"
BN"24"26;
%"TAP"
"1","(0,3425)","2","standard","I85";
;
CDS_LIB"standard"
BODY_TYPE"PLUMBING"
HDL_TAP"TRUE";
"B \NAC \NWC"12;
"S \NAC"
BN"27"23;
%"TAP"
"1","(0,3375)","2","standard","I86";
;
CDS_LIB"standard"
BODY_TYPE"PLUMBING"
HDL_TAP"TRUE";
"B \NAC \NWC"12;
"S \NAC"
BN"26"24;
%"TAP"
"1","(0,3475)","2","standard","I87";
;
CDS_LIB"standard"
BODY_TYPE"PLUMBING"
HDL_TAP"TRUE";
"B \NAC \NWC"12;
"S \NAC"
BN"28"22;
%"TAP"
"1","(0,3525)","2","standard","I88";
;
CDS_LIB"standard"
BODY_TYPE"PLUMBING"
HDL_TAP"TRUE";
"B \NAC \NWC"12;
"S \NAC"
BN"29"21;
%"TAP"
"1","(0,3575)","2","standard","I89";
;
CDS_LIB"standard"
BODY_TYPE"PLUMBING"
HDL_TAP"TRUE";
"B \NAC \NWC"12;
"S \NAC"
BN"30"20;
%"TAP"
"1","(0,-275)","2","standard","I9";
;
CDS_LIB"standard"
BODY_TYPE"PLUMBING"
HDL_TAP"TRUE";
"B \NAC \NWC"9;
"S \NAC"
BN"1"97;
%"TAP"
"1","(0,3625)","2","standard","I90";
;
CDS_LIB"standard"
BODY_TYPE"PLUMBING"
HDL_TAP"TRUE";
"B \NAC \NWC"12;
"S \NAC"
BN"31"19;
%"TAP"
"1","(3425,-125)","0","standard","I96";
;
CDS_LIB"standard"
BODY_TYPE"PLUMBING"
HDL_TAP"TRUE";
"B \NAC \NWC"6;
"S \NAC"
BN"0"120;
%"TAP"
"1","(3425,-75)","0","standard","I97";
;
CDS_LIB"standard"
BODY_TYPE"PLUMBING"
HDL_TAP"TRUE";
"B \NAC \NWC"6;
"S \NAC"
BN"1"121;
%"TAP"
"1","(3425,25)","0","standard","I98";
;
CDS_LIB"standard"
BODY_TYPE"PLUMBING"
HDL_TAP"TRUE";
"B \NAC \NWC"6;
"S \NAC"
BN"3"123;
%"TAP"
"1","(3425,-25)","0","standard","I99";
;
CDS_LIB"standard"
BODY_TYPE"PLUMBING"
HDL_TAP"TRUE";
"B \NAC \NWC"6;
"S \NAC"
BN"2"122;
END.
